(kicad_pcb
	(version 20241229)
	(generator "pcbnew")
	(generator_version "9.0")
	(general
		(thickness 1.61)
		(legacy_teardrops no)
	)
	(paper "A3")
	(title_block
		(title "RDIMM DDR5 Tester")
		(date "2026-05-21")
		(rev "2.2.0")
		(company "Antmicro")
		(comment 9 "footprints 628-632 of 796")
	)
	(layers
		(0 "F.Cu" signal)
		(4 "In1.Cu" power)
		(6 "In2.Cu" mixed)
		(8 "In3.Cu" power)
		(10 "In4.Cu" mixed)
		(12 "In5.Cu" power)
		(14 "In6.Cu" mixed)
		(16 "In7.Cu" power)
		(18 "In8.Cu" power)
		(20 "In9.Cu" mixed)
		(22 "In10.Cu" power)
		(2 "B.Cu" signal)
		(9 "F.Adhes" user "F.Adhesive")
		(11 "B.Adhes" user "B.Adhesive")
		(13 "F.Paste" user)
		(15 "B.Paste" user)
		(5 "F.SilkS" user "F.Silkscreen")
		(7 "B.SilkS" user "B.Silkscreen")
		(1 "F.Mask" user)
		(3 "B.Mask" user)
		(17 "Dwgs.User" user "User.Drawings")
		(19 "Cmts.User" user "User.Comments")
		(21 "Eco1.User" user "User.Eco1")
		(23 "Eco2.User" user "User.Eco2")
		(25 "Edge.Cuts" user)
		(27 "Margin" user)
		(31 "F.CrtYd" user "F.Courtyard")
		(29 "B.CrtYd" user "B.Courtyard")
		(35 "F.Fab" user)
		(33 "B.Fab" user)
	)
	(footprint "antmicro-footprints:R_0402_1005Metric"
		(layer "B.Cu")
		(at 247.845 110.625)
		(descr "Resistor SMD 0402")
		(tags "resistor SMD 0402")
		(property "Reference" "R128"
			(at -3.895 0.45 0)
			(layer "B.SilkS")
			(effects
				(font
					(size 0.7 0.7)
					(thickness 0.15)
				)
				(justify right bottom mirror)
			)
		)
		(property "Value" "R_10k_0402"
			(at -1.011843 -1.772047 0)
			(layer "B.Fab")
			(effects
				(font
					(size 0.7 0.7)
					(thickness 0.15)
				)
				(justify right bottom mirror)
			)
		)
		(property "Datasheet" "https://www.bourns.com/docs/product-datasheets/cr.pdf"
			(at 0 0 0)
			(layer "F.Fab")
			(hide yes)
			(effects
				(font
					(size 1.27 1.27)
					(thickness 0.15)
				)
			)
		)
		(property "MPN" "CR0402-FX-1002GLF"
			(at 0 0 0)
			(unlocked yes)
			(layer "B.Fab")
			(hide yes)
			(effects
				(font
					(size 1 1)
					(thickness 0.15)
				)
				(justify mirror)
			)
		)
		(property "Manufacturer" "Bourns"
			(at 0 0 0)
			(unlocked yes)
			(layer "B.Fab")
			(hide yes)
			(effects
				(font
					(size 1 1)
					(thickness 0.15)
				)
				(justify mirror)
			)
		)
		(property "License" "Apache-2.0"
			(at 0 0 0)
			(unlocked yes)
			(layer "B.Fab")
			(hide yes)
			(effects
				(font
					(size 1 1)
					(thickness 0.15)
				)
				(justify mirror)
			)
		)
		(property "Author" "Antmicro"
			(at 0 0 0)
			(unlocked yes)
			(layer "B.Fab")
			(hide yes)
			(effects
				(font
					(size 1 1)
					(thickness 0.15)
				)
				(justify mirror)
			)
		)
		(property "Val" "10k"
			(at 0 0 0)
			(unlocked yes)
			(layer "B.Fab")
			(hide yes)
			(effects
				(font
					(size 1 1)
					(thickness 0.15)
				)
				(justify mirror)
			)
		)
		(property "Tolerance" "1%"
			(at 0 0 0)
			(unlocked yes)
			(layer "B.Fab")
			(hide yes)
			(effects
				(font
					(size 1 1)
					(thickness 0.15)
				)
				(justify mirror)
			)
		)
		(sheetname "/DDR5 RDIMM/")
		(sheetfile "ddr5-rdimm.kicad_sch")
		(attr smd)
		(fp_rect
			(start -0.925 0.47)
			(end 0.925 -0.47)
			(stroke
				(width 0.05)
				(type default)
			)
			(fill no)
			(layer "B.CrtYd")
		)
		(fp_rect
			(start -0.5 0.25)
			(end 0.5 -0.25)
			(stroke
				(width 0.15)
				(type solid)
			)
			(fill no)
			(layer "B.Fab")
		)
		(fp_text user "${REFERENCE}"
			(at -0.95 -3.168 180)
			(layer "B.Fab")
			(effects
				(font
					(size 0.7 0.7)
					(thickness 0.15)
				)
				(justify left bottom mirror)
			)
		)
		(fp_text user "Author: Antmicro"
			(at -0.95 -4.169 180)
			(layer "B.Fab")
			(effects
				(font
					(size 0.7 0.7)
					(thickness 0.15)
				)
				(justify left bottom mirror)
			)
		)
		(fp_text user "License: Apache-2.0"
			(at -0.95 -5.169 180)
			(layer "B.Fab")
			(effects
				(font
					(size 0.7 0.7)
					(thickness 0.15)
				)
				(justify left bottom mirror)
			)
		)
		(pad "1" smd roundrect
			(at -0.48 0)
			(size 0.59 0.64)
			(layers "B.Cu" "B.Mask" "B.Paste")
			(roundrect_rratio 0.25)
			(net 1 "GND")
			(pintype "passive")
		)
		(pad "2" smd roundrect
			(at 0.48 0)
			(size 0.59 0.64)
			(layers "B.Cu" "B.Mask" "B.Paste")
			(roundrect_rratio 0.25)
			(net 461 "/DDR5 RDIMM/HSA")
			(pintype "passive")
		)
	)
	(footprint "antmicro-footprints:Coax_Conn_U.FL"
		(layer "B.Cu")
		(at 169.898 102.646 90)
		(descr "https://media.digikey.com/pdf/Data%20Sheets/Hirose%20PDFs/UFL%20Series.pdf")
		(property "Reference" "J15"
			(at -3.204 -1.998 180)
			(layer "B.SilkS")
			(effects
				(font
					(size 0.7 0.7)
					(thickness 0.15)
				)
				(justify right bottom mirror)
			)
		)
		(property "Value" "U_FL-R-SMT-1"
			(at -4.13 -2.52 90)
			(layer "B.Fab")
			(effects
				(font
					(size 0.7 0.7)
					(thickness 0.15)
				)
				(justify right bottom mirror)
			)
		)
		(property "Datasheet" "https://media.digikey.com/pdf/Data%20Sheets/Hirose%20PDFs/UFL%20Series.pdf"
			(at 0 0 90)
			(layer "F.Fab")
			(hide yes)
			(effects
				(font
					(size 1.27 1.27)
					(thickness 0.15)
				)
			)
		)
		(property "MPN" "U.FL-R-SMT-1(10)"
			(at 0 0 90)
			(unlocked yes)
			(layer "B.Fab")
			(hide yes)
			(effects
				(font
					(size 1 1)
					(thickness 0.15)
				)
				(justify mirror)
			)
		)
		(property "Manufacturer" "Hirose Electric"
			(at 0 0 90)
			(unlocked yes)
			(layer "B.Fab")
			(hide yes)
			(effects
				(font
					(size 1 1)
					(thickness 0.15)
				)
				(justify mirror)
			)
		)
		(property "Author" "Antmicro"
			(at 0 0 90)
			(unlocked yes)
			(layer "B.Fab")
			(hide yes)
			(effects
				(font
					(size 1 1)
					(thickness 0.15)
				)
				(justify mirror)
			)
		)
		(property "License" "Apache-2.0"
			(at 0 0 90)
			(unlocked yes)
			(layer "B.Fab")
			(hide yes)
			(effects
				(font
					(size 1 1)
					(thickness 0.15)
				)
				(justify mirror)
			)
		)
		(sheetname "/Debug FTDI + VNA/")
		(sheetfile "debug-ftdi.kicad_sch")
		(attr smd)
		(fp_line
			(start 1.588 -1.648)
			(end 1.088 -1.648)
			(stroke
				(width 0.15)
				(type solid)
			)
			(layer "B.SilkS")
		)
		(fp_line
			(start 1.588 -1.648)
			(end 1.588 -1.325)
			(stroke
				(width 0.15)
				(type solid)
			)
			(layer "B.SilkS")
		)
		(fp_line
			(start -1.613 -1.648)
			(end -1.113 -1.648)
			(stroke
				(width 0.15)
				(type solid)
			)
			(layer "B.SilkS")
		)
		(fp_line
			(start -1.613 -1.648)
			(end -1.613 -1.325)
			(stroke
				(width 0.15)
				(type solid)
			)
			(layer "B.SilkS")
		)
		(fp_line
			(start 1.588 1.651)
			(end 1.588 1.325)
			(stroke
				(width 0.15)
				(type solid)
			)
			(layer "B.SilkS")
		)
		(fp_line
			(start 1.588 1.651)
			(end 1.088 1.651)
			(stroke
				(width 0.15)
				(type solid)
			)
			(layer "B.SilkS")
		)
		(fp_line
			(start -1.613 1.651)
			(end -1.613 1.325)
			(stroke
				(width 0.15)
				(type solid)
			)
			(layer "B.SilkS")
		)
		(fp_line
			(start -1.613 1.651)
			(end -1.113 1.651)
			(stroke
				(width 0.15)
				(type solid)
			)
			(layer "B.SilkS")
		)
		(fp_rect
			(start -2 2.051)
			(end 1.999 -2.05)
			(stroke
				(width 0.05)
				(type solid)
			)
			(fill no)
			(layer "B.CrtYd")
		)
		(fp_line
			(start 1.487 -1.55)
			(end 1.487 1.551)
			(stroke
				(width 0.15)
				(type solid)
			)
			(layer "B.Fab")
		)
		(fp_line
			(start -1.512 -1.55)
			(end 1.487 -1.55)
			(stroke
				(width 0.15)
				(type solid)
			)
			(layer "B.Fab")
		)
		(fp_line
			(start -1.512 -1.55)
			(end -1.512 1.551)
			(stroke
				(width 0.15)
				(type solid)
			)
			(layer "B.Fab")
		)
		(fp_line
			(start -1.512 1.551)
			(end 1.487 1.551)
			(stroke
				(width 0.15)
				(type solid)
			)
			(layer "B.Fab")
		)
		(fp_text user "License: Apache-2.0"
			(at -4.13 -5.72 270)
			(layer "B.Fab")
			(effects
				(font
					(size 0.7 0.7)
					(thickness 0.15)
				)
				(justify left bottom mirror)
			)
		)
		(fp_text user "${REFERENCE}"
			(at -4.13 -6.92 270)
			(layer "B.Fab")
			(effects
				(font
					(size 0.7 0.7)
					(thickness 0.15)
				)
				(justify left bottom mirror)
			)
		)
		(fp_text user "Author: Antmicro"
			(at -4.13 -4.52 270)
			(layer "B.Fab")
			(effects
				(font
					(size 0.7 0.7)
					(thickness 0.15)
				)
				(justify left bottom mirror)
			)
		)
		(pad "1" smd rect
			(at -0.012 -1.499 90)
			(size 1 1.05)
			(layers "B.Cu" "B.Mask" "B.Paste")
			(net 371 "Net-(J15-Pad1)")
			(pintype "passive")
		)
		(pad "SH1" smd rect
			(at 1.463 0 90)
			(size 1.05 2.2)
			(layers "B.Cu" "B.Mask" "B.Paste")
			(net 1 "GND")
			(pintype "passive")
		)
		(pad "SH2" smd rect
			(at -1.488 0 90)
			(size 1.05 2.2)
			(layers "B.Cu" "B.Mask" "B.Paste")
			(net 1 "GND")
			(pintype "passive")
		)
		(zone
			(net 0)
			(net_name "")
			(layer "B.Cu")
			(hatch edge 0.508)
			(connect_pads
				(clearance 0)
			)
			(min_thickness 0.254)
			(filled_areas_thickness no)
			(keepout
				(tracks not_allowed)
				(vias not_allowed)
				(pads not_allowed)
				(copperpour not_allowed)
				(footprints not_allowed)
			)
			(placement
				(enabled no)
				(sheetname "")
			)
			(fill
				(thermal_gap 0.508)
				(thermal_bridge_width 0.508)
			)
			(polygon
				(pts
					(xy 168.938 101.716) (xy 168.938 103.596) (xy 170.998 103.596) (xy 170.998 101.716)
				)
			)
		)
	)
	(footprint "antmicro-footprints:C_0402_1005Metric"
		(layer "B.Cu")
		(at 149.084499 160.429 90)
		(descr "Capacitor SMD 0402")
		(tags "capacitor SMD 0402")
		(property "Reference" "C236"
			(at 1.433 0.515501 90)
			(layer "B.SilkS")
			(effects
				(font
					(size 0.7 0.7)
					(thickness 0.15)
				)
				(justify right bottom mirror)
			)
		)
		(property "Value" "C_100n_0402"
			(at -1.022927 -2.155213 90)
			(layer "B.Fab")
			(effects
				(font
					(size 0.7 0.7)
					(thickness 0.15)
				)
				(justify right bottom mirror)
			)
		)
		(property "Datasheet" "https://www.murata.com/products/productdetail?partno=GRM155R61H104KE14%23"
			(at 0 0 90)
			(layer "F.Fab")
			(hide yes)
			(effects
				(font
					(size 1.27 1.27)
					(thickness 0.15)
				)
			)
		)
		(property "MPN" "GRM155R61H104KE14D"
			(at 0 0 90)
			(unlocked yes)
			(layer "B.Fab")
			(hide yes)
			(effects
				(font
					(size 1 1)
					(thickness 0.15)
				)
				(justify mirror)
			)
		)
		(property "Manufacturer" "Murata"
			(at 0 0 90)
			(unlocked yes)
			(layer "B.Fab")
			(hide yes)
			(effects
				(font
					(size 1 1)
					(thickness 0.15)
				)
				(justify mirror)
			)
		)
		(property "License" "Apache-2.0"
			(at 0 0 90)
			(unlocked yes)
			(layer "B.Fab")
			(hide yes)
			(effects
				(font
					(size 1 1)
					(thickness 0.15)
				)
				(justify mirror)
			)
		)
		(property "Author" "Antmicro"
			(at 0 0 90)
			(unlocked yes)
			(layer "B.Fab")
			(hide yes)
			(effects
				(font
					(size 1 1)
					(thickness 0.15)
				)
				(justify mirror)
			)
		)
		(property "Val" "100n"
			(at 0 0 90)
			(unlocked yes)
			(layer "B.Fab")
			(hide yes)
			(effects
				(font
					(size 1 1)
					(thickness 0.15)
				)
				(justify mirror)
			)
		)
		(property "Voltage" "50V"
			(at 0 0 90)
			(unlocked yes)
			(layer "B.Fab")
			(hide yes)
			(effects
				(font
					(size 1 1)
					(thickness 0.15)
				)
				(justify mirror)
			)
		)
		(property "Dielectric" "X5R"
			(at 0 0 90)
			(unlocked yes)
			(layer "B.Fab")
			(hide yes)
			(effects
				(font
					(size 1 1)
					(thickness 0.15)
				)
				(justify mirror)
			)
		)
		(sheetname "/Debug FTDI + VNA/")
		(sheetfile "debug-ftdi.kicad_sch")
		(attr smd)
		(fp_rect
			(start -0.925 0.47)
			(end 0.925 -0.47)
			(stroke
				(width 0.05)
				(type default)
			)
			(fill no)
			(layer "B.CrtYd")
		)
		(fp_line
			(start 0.504 -0.248)
			(end -0.494 -0.248)
			(stroke
				(width 0.15)
				(type solid)
			)
			(layer "B.Fab")
		)
		(fp_line
			(start -0.494 -0.248)
			(end -0.494 0.25)
			(stroke
				(width 0.15)
				(type solid)
			)
			(layer "B.Fab")
		)
		(fp_line
			(start 0.504 0.25)
			(end 0.504 -0.248)
			(stroke
				(width 0.15)
				(type solid)
			)
			(layer "B.Fab")
		)
		(fp_line
			(start -0.494 0.25)
			(end 0.504 0.25)
			(stroke
				(width 0.15)
				(type solid)
			)
			(layer "B.Fab")
		)
		(fp_text user "Author: Antmicro"
			(at -0.939 -3.399 270)
			(layer "B.Fab")
			(effects
				(font
					(size 0.7 0.7)
					(thickness 0.15)
				)
				(justify left bottom mirror)
			)
		)
		(fp_text user "License: Apache-2.0"
			(at -0.939 -5.799 270)
			(layer "B.Fab")
			(effects
				(font
					(size 0.7 0.7)
					(thickness 0.15)
				)
				(justify left bottom mirror)
			)
		)
		(fp_text user "${REFERENCE}"
			(at -0.939 -4.599 270)
			(layer "B.Fab")
			(effects
				(font
					(size 0.7 0.7)
					(thickness 0.15)
				)
				(justify left bottom mirror)
			)
		)
		(pad "1" smd roundrect
			(at -0.48 0 90)
			(size 0.59 0.64)
			(layers "B.Cu" "B.Mask" "B.Paste")
			(roundrect_rratio 0.25)
			(net 1 "GND")
			(pintype "passive")
		)
		(pad "2" smd roundrect
			(at 0.48 0 90)
			(size 0.59 0.64)
			(layers "B.Cu" "B.Mask" "B.Paste")
			(roundrect_rratio 0.25)
			(net 151 "+3V3")
			(pintype "passive")
		)
	)
	(footprint "antmicro-footprints:R_0402_1005Metric"
		(layer "B.Cu")
		(at 235.59 134.755 90)
		(descr "Resistor SMD 0402")
		(tags "resistor SMD 0402")
		(property "Reference" "R124"
			(at -3.745 0.46 90)
			(layer "B.SilkS")
			(effects
				(font
					(size 0.7 0.7)
					(thickness 0.15)
				)
				(justify right bottom mirror)
			)
		)
		(property "Value" "R_4k7_0402"
			(at -1.011843 -1.772047 90)
			(layer "B.Fab")
			(effects
				(font
					(size 0.7 0.7)
					(thickness 0.15)
				)
				(justify right bottom mirror)
			)
		)
		(property "Datasheet" "https://www.bourns.com/docs/product-datasheets/cr.pdf"
			(at 0 0 90)
			(layer "F.Fab")
			(hide yes)
			(effects
				(font
					(size 1.27 1.27)
					(thickness 0.15)
				)
			)
		)
		(property "Manufacturer" "Bourns"
			(at 0 0 90)
			(unlocked yes)
			(layer "B.Fab")
			(hide yes)
			(effects
				(font
					(size 1 1)
					(thickness 0.15)
				)
				(justify mirror)
			)
		)
		(property "MPN" "CR0402-FX-4701GLF"
			(at 0 0 90)
			(unlocked yes)
			(layer "B.Fab")
			(hide yes)
			(effects
				(font
					(size 1 1)
					(thickness 0.15)
				)
				(justify mirror)
			)
		)
		(property "Val" "4k7"
			(at 0 0 90)
			(unlocked yes)
			(layer "B.Fab")
			(hide yes)
			(effects
				(font
					(size 1 1)
					(thickness 0.15)
				)
				(justify mirror)
			)
		)
		(property "License" "Apache-2.0"
			(at 0 0 90)
			(unlocked yes)
			(layer "B.Fab")
			(hide yes)
			(effects
				(font
					(size 1 1)
					(thickness 0.15)
				)
				(justify mirror)
			)
		)
		(property "Author" "Antmicro"
			(at 0 0 90)
			(unlocked yes)
			(layer "B.Fab")
			(hide yes)
			(effects
				(font
					(size 1 1)
					(thickness 0.15)
				)
				(justify mirror)
			)
		)
		(property "Tolerance" "1%"
			(at 0 0 90)
			(unlocked yes)
			(layer "B.Fab")
			(hide yes)
			(effects
				(font
					(size 1 1)
					(thickness 0.15)
				)
				(justify mirror)
			)
		)
		(sheetname "/I^{2}C + I3C/")
		(sheetfile "i2c.kicad_sch")
		(attr smd)
		(fp_rect
			(start -0.925 0.47)
			(end 0.925 -0.47)
			(stroke
				(width 0.05)
				(type default)
			)
			(fill no)
			(layer "B.CrtYd")
		)
		(fp_rect
			(start -0.5 0.25)
			(end 0.5 -0.25)
			(stroke
				(width 0.15)
				(type solid)
			)
			(fill no)
			(layer "B.Fab")
		)
		(fp_text user "License: Apache-2.0"
			(at -0.95 -5.169 270)
			(layer "B.Fab")
			(effects
				(font
					(size 0.7 0.7)
					(thickness 0.15)
				)
				(justify left bottom mirror)
			)
		)
		(fp_text user "Author: Antmicro"
			(at -0.95 -4.169 270)
			(layer "B.Fab")
			(effects
				(font
					(size 0.7 0.7)
					(thickness 0.15)
				)
				(justify left bottom mirror)
			)
		)
		(fp_text user "${REFERENCE}"
			(at -0.95 -3.168 270)
			(layer "B.Fab")
			(effects
				(font
					(size 0.7 0.7)
					(thickness 0.15)
				)
				(justify left bottom mirror)
			)
		)
		(pad "1" smd roundrect
			(at -0.48 0 90)
			(size 0.59 0.64)
			(layers "B.Cu" "B.Mask" "B.Paste")
			(roundrect_rratio 0.25)
			(net 201 "VDDSPD")
			(pintype "passive")
		)
		(pad "2" smd roundrect
			(at 0.48 0 90)
			(size 0.59 0.64)
			(layers "B.Cu" "B.Mask" "B.Paste")
			(roundrect_rratio 0.25)
			(net 459 "/DDR5 RDIMM/DDR.SDA")
			(pintype "passive")
		)
	)
	(footprint "antmicro-footprints:C_0402_1005Metric"
		(layer "B.Cu")
		(at 255.689499 140.75 -90)
		(descr "Capacitor SMD 0402")
		(tags "capacitor SMD 0402")
		(property "Reference" "C212"
			(at 1 -0.410501 90)
			(layer "B.SilkS")
			(effects
				(font
					(size 0.7 0.7)
					(thickness 0.15)
				)
				(justify left bottom mirror)
			)
		)
		(property "Value" "C_100n_0402"
			(at -1.022927 -2.155213 90)
			(layer "B.Fab")
			(effects
				(font
					(size 0.7 0.7)
					(thickness 0.15)
				)
				(justify left bottom mirror)
			)
		)
		(property "Datasheet" "https://www.murata.com/products/productdetail?partno=GRM155R61H104KE14%23"
			(at 0 0 270)
			(layer "F.Fab")
			(hide yes)
			(effects
				(font
					(size 1.27 1.27)
					(thickness 0.15)
				)
			)
		)
		(property "Manufacturer" "Murata"
			(at 0 0 270)
			(unlocked yes)
			(layer "B.Fab")
			(hide yes)
			(effects
				(font
					(size 1 1)
					(thickness 0.15)
				)
				(justify mirror)
			)
		)
		(property "MPN" "GRM155R61H104KE14D"
			(at 0 0 270)
			(unlocked yes)
			(layer "B.Fab")
			(hide yes)
			(effects
				(font
					(size 1 1)
					(thickness 0.15)
				)
				(justify mirror)
			)
		)
		(property "Val" "100n"
			(at 0 0 270)
			(unlocked yes)
			(layer "B.Fab")
			(hide yes)
			(effects
				(font
					(size 1 1)
					(thickness 0.15)
				)
				(justify mirror)
			)
		)
		(property "License" "Apache-2.0"
			(at 0 0 270)
			(unlocked yes)
			(layer "B.Fab")
			(hide yes)
			(effects
				(font
					(size 1 1)
					(thickness 0.15)
				)
				(justify mirror)
			)
		)
		(property "Author" "Antmicro"
			(at 0 0 270)
			(unlocked yes)
			(layer "B.Fab")
			(hide yes)
			(effects
				(font
					(size 1 1)
					(thickness 0.15)
				)
				(justify mirror)
			)
		)
		(property "Voltage" "50V"
			(at 0 0 270)
			(unlocked yes)
			(layer "B.Fab")
			(hide yes)
			(effects
				(font
					(size 1 1)
					(thickness 0.15)
				)
				(justify mirror)
			)
		)
		(property "Dielectric" "X5R"
			(at 0 0 270)
			(unlocked yes)
			(layer "B.Fab")
			(hide yes)
			(effects
				(font
					(size 1 1)
					(thickness 0.15)
				)
				(justify mirror)
			)
		)
		(sheetname "/Supply/")
		(sheetfile "supply.kicad_sch")
		(attr smd)
		(fp_rect
			(start -0.925 0.47)
			(end 0.925 -0.47)
			(stroke
				(width 0.05)
				(type default)
			)
			(fill no)
			(layer "B.CrtYd")
		)
		(fp_line
			(start -0.494 0.25)
			(end 0.504 0.25)
			(stroke
				(width 0.15)
				(type solid)
			)
			(layer "B.Fab")
		)
		(fp_line
			(start 0.504 0.25)
			(end 0.504 -0.248)
			(stroke
				(width 0.15)
				(type solid)
			)
			(layer "B.Fab")
		)
		(fp_line
			(start -0.494 -0.248)
			(end -0.494 0.25)
			(stroke
				(width 0.15)
				(type solid)
			)
			(layer "B.Fab")
		)
		(fp_line
			(start 0.504 -0.248)
			(end -0.494 -0.248)
			(stroke
				(width 0.15)
				(type solid)
			)
			(layer "B.Fab")
		)
		(fp_text user "Author: Antmicro"
			(at -0.939 -3.399 90)
			(layer "B.Fab")
			(effects
				(font
					(size 0.7 0.7)
					(thickness 0.15)
				)
				(justify left bottom mirror)
			)
		)
		(fp_text user "License: Apache-2.0"
			(at -0.939 -5.799 90)
			(layer "B.Fab")
			(effects
				(font
					(size 0.7 0.7)
					(thickness 0.15)
				)
				(justify left bottom mirror)
			)
		)
		(fp_text user "${REFERENCE}"
			(at -0.939 -4.599 90)
			(layer "B.Fab")
			(effects
				(font
					(size 0.7 0.7)
					(thickness 0.15)
				)
				(justify left bottom mirror)
			)
		)
		(pad "1" smd roundrect
			(at -0.48 0 270)
			(size 0.59 0.64)
			(layers "B.Cu" "B.Mask" "B.Paste")
			(roundrect_rratio 0.25)
			(net 1 "GND")
			(pintype "passive")
		)
		(pad "2" smd roundrect
			(at 0.48 0 270)
			(size 0.59 0.64)
			(layers "B.Cu" "B.Mask" "B.Paste")
			(roundrect_rratio 0.25)
			(net 38 "+3V3_AON")
			(pintype "passive")
		)
	)
)
